FILE_TYPE = MACRO_DRAWING;
SET COLOR_WIRE YELLOW;
SET COLOR_PROP ORANGE;
SET COLOR_DOT WHITE;
SET COLOR_ARC YELLOW;
SET COLOR_BODY GREEN;
SET COLOR_NOTE PURPLE;
SET PROP_DISPLAY VALUE;
SET PAGE_NUMBER P321;
FORCEADD Q_RES..1
(1050 1200);
FORCEPROP 1 LAST PART_NUMBER CS03322FB03
J 0
(925 1100);
DISPLAY 0.510638 (925 1100);
DISPLAY INVISIBLE (925 1100);
FORCEPROP 1 LAST MATERIAL CHIP
J 0
(1275 1200);
DISPLAY 0.510638 (1275 1200);
FORCEPROP 1 LAST VALUE 33.2
J 2
(1250 1200);
DISPLAY 0.510638 (1250 1200);
FORCEPROP 1 LAST $LOCATION R4621
J 0
(825 1200);
DISPLAY 0.638298 (825 1200);
FORCEPROP 1 LASTPIN (950 1200) $PN 1
J 0
(962 1212);
DISPLAY 0.787234 (962 1212);
PAINT MONO (962 1212);
FORCEPROP 1 LASTPIN (1150 1200) $PN 2
J 0
(1112 1212);
DISPLAY 0.787234 (1112 1212);
PAINT MONO (1112 1212);
FORCEPROP 1 LAST PATH I101
J 0
(1000 1350);
DISPLAY 0.978723 (1000 1350);
PAINT WHITE (1000 1350);
DISPLAY INVISIBLE (1000 1350);
FORCEPROP 2 LAST CDS_LIB pure_quanta
J 0
(1050 1200);
DISPLAY INVISIBLE (1050 1200);
FORCEPROP 1 LAST PACK_TYPE 0402LF
J 0
(1350 1200);
DISPLAY 0.510638 (1350 1200);
DISPLAY INVISIBLE (1350 1200);
FORCEPROP 1 LAST TOLERANCE 1%
J 0
(1275 1200);
DISPLAY 0.510638 (1275 1200);
DISPLAY INVISIBLE (1275 1200);
FORCEPROP 1 LAST WATTAGE 1/16W
J 2
(1200 1150);
DISPLAY 0.510638 (1200 1150);
DISPLAY INVISIBLE (1200 1150);
FORCEPROP 0 LAST CDS_LOCATION R4621
J 0
(875 1250);
DISPLAY 1.021277 (875 1250);
DISPLAY INVISIBLE (875 1250);
FORCEPROP 0 LAST $SEC 1
J 0
(875 1250);
DISPLAY 0.680851 (875 1250);
PAINT MONO (875 1250);
DISPLAY INVISIBLE (875 1250);
FORCEPROP 0 LAST CDS_SEC 1
J 0
(875 1250);
DISPLAY 1.021277 (875 1250);
DISPLAY INVISIBLE (875 1250);
FORCEADD OFFPAGE..2
(2625 1200);
FORCEPROP 2 LAST $XR0 240 
J 0
(2814 1200);
DISPLAY 0.638298 (2814 1200);
PAINT MONO (2814 1200);
FORCEPROP 2 LAST PATH I102
J 0
(2825 1250);
DISPLAY 1.021277 (2825 1250);
DISPLAY INVISIBLE (2825 1250);
FORCEPROP 1 LAST COMMENT_BODY TRUE
J 0
(2580 1105);
DISPLAY 0.872340 (2580 1105);
PAINT GREEN (2580 1105);
DISPLAY INVISIBLE (2580 1105);
FORCEPROP 1 LAST OFFPAGE TRUE
J 0
(2950 1075);
DISPLAY 0.872340 (2950 1075);
DISPLAY INVISIBLE (2950 1075);
FORCEPROP 2 LAST CDS_LIB standard
J 0
(2625 1200);
DISPLAY INVISIBLE (2625 1200);
FORCEADD UNIVERSAL_GND..1
R 2
(900 1575);
FORCEPROP 3 LASTPIN (900 1625) SIG_NAME GND\g
J 0
(910 1635);
DISPLAY 0.659574 (910 1635);
PAINT MONO (910 1635);
DISPLAY INVISIBLE (910 1635);
FORCEPROP 2 LAST CDS_LIB logical_power
J 0
(900 1575);
DISPLAY INVISIBLE (900 1575);
FORCEPROP 1 LAST HDL_POWER GND
J 1
(875 1500);
DISPLAY 0.872340 (875 1500);
PAINT GREEN (875 1500);
DISPLAY INVISIBLE (875 1500);
FORCEPROP 1 LAST PATH I70
J 2
(825 1575);
DISPLAY 0.872340 (825 1575);
PAINT AQUA (825 1575);
DISPLAY INVISIBLE (825 1575);
FORCEADD OFFPAGE..2
(2625 1400);
FORCEPROP 2 LAST $XR1 255 
J 0
(2934 1400);
DISPLAY 0.638298 (2934 1400);
PAINT MONO (2934 1400);
FORCEPROP 2 LAST $XR0 216 
J 0
(2814 1400);
DISPLAY 0.638298 (2814 1400);
PAINT MONO (2814 1400);
FORCEPROP 2 LAST PATH I71
J 0
(2800 1475);
DISPLAY 1.021277 (2800 1475);
DISPLAY INVISIBLE (2800 1475);
FORCEPROP 1 LAST COMMENT_BODY TRUE
J 0
(2580 1305);
DISPLAY 0.872340 (2580 1305);
PAINT GREEN (2580 1305);
DISPLAY INVISIBLE (2580 1305);
FORCEPROP 1 LAST OFFPAGE TRUE
J 0
(2950 1275);
DISPLAY 0.872340 (2950 1275);
DISPLAY INVISIBLE (2950 1275);
FORCEPROP 2 LAST CDS_LIB standard
J 0
(2625 1400);
DISPLAY INVISIBLE (2625 1400);
FORCEADD OFFPAGE..2
(2625 1350);
FORCEPROP 2 LAST $XR0 216 
J 0
(2814 1350);
DISPLAY 0.638298 (2814 1350);
PAINT MONO (2814 1350);
FORCEPROP 2 LAST PATH I72
J 0
(2800 1425);
DISPLAY 1.021277 (2800 1425);
DISPLAY INVISIBLE (2800 1425);
FORCEPROP 1 LAST COMMENT_BODY TRUE
J 0
(2580 1255);
DISPLAY 0.872340 (2580 1255);
PAINT GREEN (2580 1255);
DISPLAY INVISIBLE (2580 1255);
FORCEPROP 1 LAST OFFPAGE TRUE
J 0
(2950 1225);
DISPLAY 0.872340 (2950 1225);
DISPLAY INVISIBLE (2950 1225);
FORCEPROP 2 LAST CDS_LIB standard
J 0
(2625 1350);
DISPLAY INVISIBLE (2625 1350);
FORCEADD OFFPAGE..2
(2625 1300);
FORCEPROP 2 LAST $XR0 216 
J 0
(2814 1300);
DISPLAY 0.638298 (2814 1300);
PAINT MONO (2814 1300);
FORCEPROP 2 LAST CDS_LIB standard
J 0
(2625 1300);
DISPLAY INVISIBLE (2625 1300);
FORCEPROP 1 LAST OFFPAGE TRUE
J 0
(2950 1175);
DISPLAY 0.872340 (2950 1175);
DISPLAY INVISIBLE (2950 1175);
FORCEPROP 1 LAST COMMENT_BODY TRUE
J 0
(2580 1205);
DISPLAY 0.872340 (2580 1205);
PAINT GREEN (2580 1205);
DISPLAY INVISIBLE (2580 1205);
FORCEPROP 2 LAST PATH I73
J 0
(2800 1375);
DISPLAY 1.021277 (2800 1375);
DISPLAY INVISIBLE (2800 1375);
FORCEADD UNIVERSAL_GND..1
R 2
(1625 1475);
FORCEPROP 3 LASTPIN (1625 1525) SIG_NAME GND\g
J 0
(1635 1535);
DISPLAY 0.659574 (1635 1535);
PAINT MONO (1635 1535);
DISPLAY INVISIBLE (1635 1535);
FORCEPROP 1 LAST PATH I74
J 2
(1550 1475);
DISPLAY 0.872340 (1550 1475);
PAINT AQUA (1550 1475);
DISPLAY INVISIBLE (1550 1475);
FORCEPROP 1 LAST HDL_POWER GND
J 1
(1600 1400);
DISPLAY 0.872340 (1600 1400);
PAINT GREEN (1600 1400);
DISPLAY INVISIBLE (1600 1400);
FORCEPROP 2 LAST CDS_LIB logical_power
R 3
J 0
(1625 1475);
PAINT MONO (1625 1475);
DISPLAY INVISIBLE (1625 1475);
FORCEADD UNIVERSAL_POWER..1
(900 2475);
FORCEPROP 3 LASTPIN (900 2425) SIG_NAME P3V3\g
J 0
(910 2435);
DISPLAY 0.659574 (910 2435);
PAINT MONO (910 2435);
DISPLAY INVISIBLE (910 2435);
FORCEPROP 1 LAST HDL_POWER P3V3
J 1
(900 2525);
DISPLAY 0.872340 (900 2525);
PAINT GREEN (900 2525);
FORCEPROP 2 LAST CDS_LIB logical_power
J 0
(900 2475);
DISPLAY INVISIBLE (900 2475);
FORCEPROP 1 LAST PATH I75
J 0
(950 2500);
DISPLAY 0.872340 (950 2500);
PAINT AQUA (950 2500);
DISPLAY INVISIBLE (950 2500);
FORCEADD Q_RES..1
(1150 1550);
FORCEPROP 1 LAST PART_NUMBER CS21002FB06
J 0
(1025 1500);
DISPLAY 0.510638 (1025 1500);
DISPLAY INVISIBLE (1025 1500);
FORCEPROP 1 LAST MATERIAL CHIP
J 0
(1275 1550);
DISPLAY 0.510638 (1275 1550);
FORCEPROP 1 LAST VALUE 1K
J 2
(1425 1550);
DISPLAY 0.510638 (1425 1550);
FORCEPROP 1 LAST $LOCATION R4029
J 0
(950 1550);
DISPLAY 0.638298 (950 1550);
FORCEPROP 1 LASTPIN (1050 1550) $PN 1
J 0
(1062 1562);
DISPLAY 0.787234 (1062 1562);
PAINT MONO (1062 1562);
FORCEPROP 1 LASTPIN (1250 1550) $PN 2
J 0
(1212 1562);
DISPLAY 0.787234 (1212 1562);
PAINT MONO (1212 1562);
FORCEPROP 1 LAST TOLERANCE 1%
J 0
(850 1525);
DISPLAY 0.510638 (850 1525);
DISPLAY INVISIBLE (850 1525);
FORCEPROP 1 LAST WATTAGE 1/16W
J 2
(800 1525);
DISPLAY 0.510638 (800 1525);
DISPLAY INVISIBLE (800 1525);
FORCEPROP 1 LAST PACK_TYPE 0402LF
J 0
(900 1525);
DISPLAY 0.510638 (900 1525);
DISPLAY INVISIBLE (900 1525);
FORCEPROP 2 LAST CDS_LIB pure_quanta
J 0
(1150 1550);
DISPLAY INVISIBLE (1150 1550);
FORCEPROP 1 LAST PATH I77
J 0
(1100 1700);
DISPLAY 0.978723 (1100 1700);
PAINT WHITE (1100 1700);
DISPLAY INVISIBLE (1100 1700);
FORCEPROP 0 LAST CDS_LOCATION R4029
J 0
(1100 1650);
DISPLAY 1.021277 (1100 1650);
DISPLAY INVISIBLE (1100 1650);
FORCEPROP 0 LAST $SEC 1
J 0
(1100 1650);
DISPLAY 0.680851 (1100 1650);
PAINT MONO (1100 1650);
DISPLAY INVISIBLE (1100 1650);
FORCEPROP 0 LAST CDS_SEC 1
J 0
(1100 1650);
DISPLAY 1.021277 (1100 1650);
DISPLAY INVISIBLE (1100 1650);
FORCEADD Q_RES..1
(1050 1400);
FORCEPROP 1 LAST PART_NUMBER CS03322FB03
J 0
(925 1300);
DISPLAY 0.510638 (925 1300);
DISPLAY INVISIBLE (925 1300);
FORCEPROP 1 LAST VALUE 33.2
J 2
(1250 1400);
DISPLAY 0.510638 (1250 1400);
FORCEPROP 1 LAST MATERIAL CHIP
J 0
(1275 1400);
DISPLAY 0.510638 (1275 1400);
FORCEPROP 1 LAST $LOCATION R4021
J 0
(825 1400);
DISPLAY 0.638298 (825 1400);
FORCEPROP 1 LASTPIN (950 1400) $PN 1
J 0
(962 1412);
DISPLAY 0.787234 (962 1412);
PAINT MONO (962 1412);
FORCEPROP 1 LASTPIN (1150 1400) $PN 2
J 0
(1112 1412);
DISPLAY 0.787234 (1112 1412);
PAINT MONO (1112 1412);
FORCEPROP 1 LAST PATH I78
J 0
(1000 1550);
DISPLAY 0.978723 (1000 1550);
PAINT WHITE (1000 1550);
DISPLAY INVISIBLE (1000 1550);
FORCEPROP 2 LAST CDS_LIB pure_quanta
J 0
(1050 1400);
DISPLAY INVISIBLE (1050 1400);
FORCEPROP 1 LAST WATTAGE 1/16W
J 2
(1200 1350);
DISPLAY 0.510638 (1200 1350);
DISPLAY INVISIBLE (1200 1350);
FORCEPROP 1 LAST TOLERANCE 1%
J 0
(1275 1400);
DISPLAY 0.510638 (1275 1400);
DISPLAY INVISIBLE (1275 1400);
FORCEPROP 1 LAST PACK_TYPE 0402LF
J 0
(1350 1400);
DISPLAY 0.510638 (1350 1400);
DISPLAY INVISIBLE (1350 1400);
FORCEPROP 0 LAST CDS_LOCATION R4021
J 0
(875 1450);
DISPLAY 1.021277 (875 1450);
DISPLAY INVISIBLE (875 1450);
FORCEPROP 0 LAST $SEC 1
J 0
(875 1450);
DISPLAY 0.680851 (875 1450);
PAINT MONO (875 1450);
DISPLAY INVISIBLE (875 1450);
FORCEPROP 0 LAST CDS_SEC 1
J 0
(875 1450);
DISPLAY 1.021277 (875 1450);
DISPLAY INVISIBLE (875 1450);
FORCEADD Q_RES..1
(1050 1350);
FORCEPROP 1 LAST PART_NUMBER CS03322FB03
J 0
(925 1250);
DISPLAY 0.510638 (925 1250);
DISPLAY INVISIBLE (925 1250);
FORCEPROP 1 LAST MATERIAL CHIP
J 0
(1275 1350);
DISPLAY 0.510638 (1275 1350);
FORCEPROP 1 LAST VALUE 33.2
J 2
(1250 1350);
DISPLAY 0.510638 (1250 1350);
FORCEPROP 1 LAST $LOCATION R4022
J 0
(825 1350);
DISPLAY 0.638298 (825 1350);
FORCEPROP 1 LASTPIN (950 1350) $PN 1
J 0
(962 1362);
DISPLAY 0.787234 (962 1362);
PAINT MONO (962 1362);
FORCEPROP 1 LASTPIN (1150 1350) $PN 2
J 0
(1112 1362);
DISPLAY 0.787234 (1112 1362);
PAINT MONO (1112 1362);
FORCEPROP 1 LAST PATH I79
J 0
(1000 1500);
DISPLAY 0.978723 (1000 1500);
PAINT WHITE (1000 1500);
DISPLAY INVISIBLE (1000 1500);
FORCEPROP 2 LAST CDS_LIB pure_quanta
J 0
(1050 1350);
DISPLAY INVISIBLE (1050 1350);
FORCEPROP 1 LAST PACK_TYPE 0402LF
J 0
(1350 1350);
DISPLAY 0.510638 (1350 1350);
DISPLAY INVISIBLE (1350 1350);
FORCEPROP 1 LAST TOLERANCE 1%
J 0
(1275 1350);
DISPLAY 0.510638 (1275 1350);
DISPLAY INVISIBLE (1275 1350);
FORCEPROP 1 LAST WATTAGE 1/16W
J 2
(1200 1300);
DISPLAY 0.510638 (1200 1300);
DISPLAY INVISIBLE (1200 1300);
FORCEPROP 0 LAST CDS_LOCATION R4022
J 0
(875 1400);
DISPLAY 1.021277 (875 1400);
DISPLAY INVISIBLE (875 1400);
FORCEPROP 0 LAST $SEC 1
J 0
(875 1400);
DISPLAY 0.680851 (875 1400);
PAINT MONO (875 1400);
DISPLAY INVISIBLE (875 1400);
FORCEPROP 0 LAST CDS_SEC 1
J 0
(875 1400);
DISPLAY 1.021277 (875 1400);
DISPLAY INVISIBLE (875 1400);
FORCEADD Q_RES..1
(1050 1300);
FORCEPROP 1 LAST PART_NUMBER CS03322FB03
J 0
(925 1200);
DISPLAY 0.510638 (925 1200);
DISPLAY INVISIBLE (925 1200);
FORCEPROP 1 LAST VALUE 33.2
J 2
(1250 1300);
DISPLAY 0.510638 (1250 1300);
FORCEPROP 1 LAST MATERIAL CHIP
J 0
(1275 1300);
DISPLAY 0.510638 (1275 1300);
FORCEPROP 1 LAST $LOCATION R4023
J 0
(825 1300);
DISPLAY 0.638298 (825 1300);
FORCEPROP 1 LASTPIN (950 1300) $PN 1
J 0
(962 1312);
DISPLAY 0.787234 (962 1312);
PAINT MONO (962 1312);
FORCEPROP 1 LASTPIN (1150 1300) $PN 2
J 0
(1112 1312);
DISPLAY 0.787234 (1112 1312);
PAINT MONO (1112 1312);
FORCEPROP 1 LAST WATTAGE 1/16W
J 2
(1200 1250);
DISPLAY 0.510638 (1200 1250);
DISPLAY INVISIBLE (1200 1250);
FORCEPROP 1 LAST TOLERANCE 1%
J 0
(1275 1300);
DISPLAY 0.510638 (1275 1300);
DISPLAY INVISIBLE (1275 1300);
FORCEPROP 1 LAST PACK_TYPE 0402LF
J 0
(1350 1300);
DISPLAY 0.510638 (1350 1300);
DISPLAY INVISIBLE (1350 1300);
FORCEPROP 2 LAST CDS_LIB pure_quanta
J 0
(1050 1300);
DISPLAY INVISIBLE (1050 1300);
FORCEPROP 1 LAST PATH I80
J 0
(1000 1450);
DISPLAY 0.978723 (1000 1450);
PAINT WHITE (1000 1450);
DISPLAY INVISIBLE (1000 1450);
FORCEPROP 0 LAST CDS_LOCATION R4023
J 0
(875 1350);
DISPLAY 1.021277 (875 1350);
DISPLAY INVISIBLE (875 1350);
FORCEPROP 0 LAST $SEC 1
J 0
(875 1350);
DISPLAY 0.680851 (875 1350);
PAINT MONO (875 1350);
DISPLAY INVISIBLE (875 1350);
FORCEPROP 0 LAST CDS_SEC 1
J 0
(875 1350);
DISPLAY 1.021277 (875 1350);
DISPLAY INVISIBLE (875 1350);
FORCEADD Q_CAP..1
R 2
(525 1850);
FORCEPROP 1 LAST PART_NUMBER CH4104K1B00
J 0
(575 1700);
DISPLAY 0.510638 (575 1700);
DISPLAY INVISIBLE (575 1700);
FORCEPROP 1 LAST TOLERANCE 10%
J 0
(575 1800);
DISPLAY 0.510638 (575 1800);
FORCEPROP 1 LAST VALUE 0.1UF
J 0
(575 1900);
DISPLAY 0.510638 (575 1900);
FORCEPROP 1 LAST VOLTAGE 25V
J 0
(575 1850);
DISPLAY 0.510638 (575 1850);
FORCEPROP 1 LAST MATERIAL X7R
J 0
(575 1750);
DISPLAY 0.510638 (575 1750);
FORCEPROP 1 LAST PACK_TYPE 0402
J 0
(575 1675);
DISPLAY 0.510638 (575 1675);
FORCEPROP 1 LAST $LOCATION C2249
J 0
(575 1950);
DISPLAY 0.808511 (575 1950);
FORCEPROP 1 LASTPIN (525 1950) $PN 1
J 2
(515 1930);
DISPLAY 0.787234 (515 1930);
PAINT MONO (515 1930);
FORCEPROP 1 LASTPIN (525 1750) $PN 2
J 2
(515 1730);
DISPLAY 0.787234 (515 1730);
PAINT MONO (515 1730);
FORCEPROP 1 LAST PATH I83
J 2
(475 2000);
DISPLAY 0.978723 (475 2000);
PAINT WHITE (475 2000);
DISPLAY INVISIBLE (475 2000);
FORCEPROP 2 LAST CDS_LIB pure_quanta
J 0
(525 1850);
DISPLAY INVISIBLE (525 1850);
FORCEPROP 0 LAST CDS_LOCATION C2249
J 0
(625 2000);
DISPLAY 1.021277 (625 2000);
DISPLAY INVISIBLE (625 2000);
FORCEPROP 0 LAST $SEC 1
J 0
(625 2000);
DISPLAY 0.680851 (625 2000);
PAINT MONO (625 2000);
DISPLAY INVISIBLE (625 2000);
FORCEPROP 0 LAST CDS_SEC 1
J 0
(625 2000);
DISPLAY 1.021277 (625 2000);
DISPLAY INVISIBLE (625 2000);
FORCEADD Q_CAP..1
(-75 1975);
FORCEPROP 1 LAST PART_NUMBER CH5104KEB02
J 0
(-25 1825);
DISPLAY 0.404255 (-25 1825);
DISPLAY INVISIBLE (-25 1825);
FORCEPROP 1 LAST VALUE 1UF
J 0
(-25 2025);
DISPLAY 0.510638 (-25 2025);
FORCEPROP 1 LAST VOLTAGE 25V
J 0
(-25 1975);
DISPLAY 0.510638 (-25 1975);
FORCEPROP 1 LAST TOLERANCE 10%
J 0
(-25 1925);
DISPLAY 0.510638 (-25 1925);
FORCEPROP 1 LAST PACK_TYPE C0402
J 0
(-25 1775);
DISPLAY 0.510638 (-25 1775);
FORCEPROP 1 LAST MATERIAL X6S
J 0
(-25 1875);
DISPLAY 0.510638 (-25 1875);
FORCEPROP 1 LAST $LOCATION C2243
J 0
(-25 2075);
DISPLAY 0.638298 (-25 2075);
FORCEPROP 1 LASTPIN (-75 2075) $PN 1
J 0
(-65 2055);
DISPLAY 0.787234 (-65 2055);
FORCEPROP 1 LASTPIN (-75 1875) $PN 2
J 0
(-65 1855);
DISPLAY 0.787234 (-65 1855);
FORCEPROP 1 LAST PATH I85
J 0
(-25 2125);
DISPLAY 0.978723 (-25 2125);
PAINT WHITE (-25 2125);
DISPLAY INVISIBLE (-25 2125);
FORCEPROP 2 LAST CDS_LIB pure_quanta
J 0
(-75 1975);
DISPLAY INVISIBLE (-75 1975);
FORCEPROP 2 LAST CDS_LOCATION C2243
J 0
(-25 2175);
DISPLAY 1.021277 (-25 2175);
DISPLAY INVISIBLE (-25 2175);
FORCEPROP 2 LAST $SEC 1
J 0
(-25 2175);
DISPLAY 0.680851 (-25 2175);
PAINT MONO (-25 2175);
DISPLAY INVISIBLE (-25 2175);
FORCEPROP 2 LAST CDS_SEC 1
J 0
(-25 2175);
DISPLAY 0.680851 (-25 2175);
DISPLAY INVISIBLE (-25 2175);
FORCEADD UNIVERSAL_GND..1
(-75 1750);
FORCEPROP 3 LASTPIN (-75 1800) SIG_NAME GND\g
J 0
(-65 1810);
DISPLAY 0.659574 (-65 1810);
PAINT MONO (-65 1810);
DISPLAY INVISIBLE (-65 1810);
FORCEPROP 1 LAST HDL_POWER GND
J 1
(-50 1675);
DISPLAY 0.872340 (-50 1675);
PAINT GREEN (-50 1675);
DISPLAY INVISIBLE (-50 1675);
FORCEPROP 1 LAST PATH I86
J 0
(0 1750);
DISPLAY 0.872340 (0 1750);
PAINT AQUA (0 1750);
DISPLAY INVISIBLE (0 1750);
FORCEPROP 2 LAST CDS_LIB logical_power
J 0
(-75 1750);
DISPLAY INVISIBLE (-75 1750);
FORCEADD UNIVERSAL_POWER..1
(-225 2225);
FORCEPROP 3 LASTPIN (-225 2175) SIG_NAME P3V3\g
J 0
(-215 2185);
DISPLAY 0.659574 (-215 2185);
PAINT MONO (-215 2185);
DISPLAY INVISIBLE (-215 2185);
FORCEPROP 1 LAST HDL_POWER P3V3
J 1
(-225 2275);
DISPLAY 0.872340 (-225 2275);
PAINT GREEN (-225 2275);
FORCEPROP 1 LAST PATH I87
J 0
(-175 2250);
DISPLAY 0.872340 (-175 2250);
PAINT AQUA (-175 2250);
DISPLAY INVISIBLE (-175 2250);
FORCEPROP 2 LAST CDS_LIB logical_power
J 0
(-225 2225);
PAINT RED (-225 2225);
DISPLAY INVISIBLE (-225 2225);
FORCEADD GTL2014PW..1
R 2
(-725 1350);
FORCEPROP 1 LAST PART_NUMBER AL002014K01
J 2
(-477 1755);
DISPLAY 0.723404 (-477 1755);
PAINT GREEN (-477 1755);
DISPLAY INVISIBLE (-477 1755);
FORCEPROP 1 LAST MATERIAL IC
J 2
(-477 1705);
DISPLAY 0.723404 (-477 1705);
PAINT GREEN (-477 1705);
FORCEPROP 2 LAST VALUE GTL2014PW
J 2
(-500 1850);
DISPLAY 1.021277 (-500 1850);
FORCEPROP 2 LAST PART_TYPE SMLF
J 2
(-500 1900);
DISPLAY 1.021277 (-500 1900);
FORCEPROP 1 LAST $LOCATION U301
J 2
(-477 1800);
DISPLAY 0.680851 (-477 1800);
PAINT GREEN (-477 1800);
FORCEPROP 2 LASTPIN (-325 1250) $PN 13
J 0
(-315 1260);
DISPLAY 0.680851 (-315 1260);
PAINT MONO (-315 1260);
FORCEPROP 2 LASTPIN (-325 1300) $PN 12
J 0
(-315 1310);
DISPLAY 0.680851 (-315 1310);
PAINT MONO (-315 1310);
FORCEPROP 2 LASTPIN (-325 1350) $PN 10
J 0
(-315 1360);
DISPLAY 0.680851 (-315 1360);
PAINT MONO (-315 1360);
FORCEPROP 2 LASTPIN (-325 1400) $PN 9
J 0
(-315 1410);
DISPLAY 0.680851 (-315 1410);
PAINT MONO (-315 1410);
FORCEPROP 2 LASTPIN (-1125 1250) $PN 2
J 2
(-1135 1260);
DISPLAY 0.680851 (-1135 1260);
PAINT MONO (-1135 1260);
FORCEPROP 2 LASTPIN (-1125 1300) $PN 3
J 2
(-1135 1310);
DISPLAY 0.680851 (-1135 1310);
PAINT MONO (-1135 1310);
FORCEPROP 2 LASTPIN (-1125 1350) $PN 5
J 2
(-1135 1360);
DISPLAY 0.680851 (-1135 1360);
PAINT MONO (-1135 1360);
FORCEPROP 2 LASTPIN (-1125 1400) $PN 6
J 2
(-1135 1410);
DISPLAY 0.680851 (-1135 1410);
PAINT MONO (-1135 1410);
FORCEPROP 2 LASTPIN (-325 1500) $PN 1
J 0
(-315 1510);
DISPLAY 0.680851 (-315 1510);
PAINT MONO (-315 1510);
FORCEPROP 2 LASTPIN (-1125 1050) $PN 7
J 2
(-1135 1060);
DISPLAY 0.680851 (-1135 1060);
PAINT MONO (-1135 1060);
FORCEPROP 2 LASTPIN (-1125 1100) $PN 8
J 2
(-1135 1110);
DISPLAY 0.680851 (-1135 1110);
PAINT MONO (-1135 1110);
FORCEPROP 2 LASTPIN (-1125 1150) $PN 11
J 2
(-1135 1160);
DISPLAY 0.680851 (-1135 1160);
PAINT MONO (-1135 1160);
FORCEPROP 2 LASTPIN (-325 1650) $PN 14
J 0
(-315 1660);
DISPLAY 0.680851 (-315 1660);
PAINT MONO (-315 1660);
FORCEPROP 2 LASTPIN (-325 1600) $PN 4
J 0
(-315 1610);
DISPLAY 0.680851 (-315 1610);
PAINT MONO (-315 1610);
FORCEPROP 1 LAST PATH I91
J 2
(-725 1350);
DISPLAY 0.723404 (-725 1350);
PAINT GREEN (-725 1350);
DISPLAY INVISIBLE (-725 1350);
FORCEPROP 2 LAST SEC_TYPE 
J 2
(-500 1950);
DISPLAY 1.021277 (-500 1950);
DISPLAY INVISIBLE (-500 1950);
FORCEPROP 2 LAST CDS_LIB pure_quanta
J 2
(-725 1350);
PAINT RED (-725 1350);
DISPLAY INVISIBLE (-725 1350);
FORCEPROP 1 LAST CDS_LMAN_SYM_OUTLINE -250,350,250,-350
J 2
(-725 1350);
DISPLAY 0.468085 (-725 1350);
PAINT GREEN (-725 1350);
DISPLAY INVISIBLE (-725 1350);
FORCEPROP 1 LAST NEEDS_NO_SIZE TRUE
J 2
(-725 1350);
DISPLAY 0.723404 (-725 1350);
PAINT GREEN (-725 1350);
DISPLAY INVISIBLE (-725 1350);
FORCEPROP 2 LAST CDS_LOCATION U301
J 0
(-500 1950);
DISPLAY 1.021277 (-500 1950);
DISPLAY INVISIBLE (-500 1950);
FORCEPROP 2 LAST SEC 1
J 2
(-500 1950);
DISPLAY 0.680851 (-500 1950);
PAINT MONO (-500 1950);
DISPLAY INVISIBLE (-500 1950);
FORCEADD UNIVERSAL_GND..1
(-1250 950);
FORCEPROP 3 LASTPIN (-1250 1000) SIG_NAME GND\g
J 0
(-1240 1010);
DISPLAY 0.659574 (-1240 1010);
PAINT MONO (-1240 1010);
DISPLAY INVISIBLE (-1240 1010);
FORCEPROP 1 LAST PATH I92
J 0
(-1175 950);
DISPLAY 0.872340 (-1175 950);
PAINT AQUA (-1175 950);
DISPLAY INVISIBLE (-1175 950);
FORCEPROP 2 LAST CDS_LIB logical_power
J 0
(-1250 950);
DISPLAY INVISIBLE (-1250 950);
FORCEPROP 1 LAST HDL_POWER GND
J 1
(-1225 875);
DISPLAY 0.872340 (-1225 875);
PAINT GREEN (-1225 875);
DISPLAY INVISIBLE (-1225 875);
FORCEADD OFFPAGE..1
(-2175 1400);
FORCEPROP 2 LAST $XR0 222 
J 0
(-2427 1400);
DISPLAY 0.638298 (-2427 1400);
PAINT MONO (-2427 1400);
FORCEPROP 2 LAST CDS_LIB standard
J 0
(-2175 1400);
DISPLAY INVISIBLE (-2175 1400);
FORCEPROP 1 LAST COMMENT_BODY TRUE
J 0
(-2050 1300);
DISPLAY 1.170213 (-2050 1300);
PAINT GREEN (-2050 1300);
DISPLAY INVISIBLE (-2050 1300);
FORCEPROP 1 LAST OFFPAGE TRUE
J 0
(-1850 1275);
DISPLAY 0.872340 (-1850 1275);
DISPLAY INVISIBLE (-1850 1275);
FORCEPROP 2 LAST PATH I94
J 0
(-2450 1450);
DISPLAY 1.021277 (-2450 1450);
DISPLAY INVISIBLE (-2450 1450);
FORCEADD OFFPAGE..1
(-2175 1350);
FORCEPROP 2 LAST $XR0 118 
J 0
(-2427 1350);
DISPLAY 0.638298 (-2427 1350);
PAINT MONO (-2427 1350);
FORCEPROP 1 LAST OFFPAGE TRUE
J 0
(-1850 1225);
DISPLAY 0.872340 (-1850 1225);
DISPLAY INVISIBLE (-1850 1225);
FORCEPROP 1 LAST COMMENT_BODY TRUE
J 0
(-2050 1250);
DISPLAY 1.170213 (-2050 1250);
PAINT GREEN (-2050 1250);
DISPLAY INVISIBLE (-2050 1250);
FORCEPROP 2 LAST PATH I95
J 0
(-2125 1425);
DISPLAY 1.021277 (-2125 1425);
DISPLAY INVISIBLE (-2125 1425);
FORCEPROP 2 LAST CDS_LIB standard
J 0
(-2175 1350);
DISPLAY INVISIBLE (-2175 1350);
FORCEADD OFFPAGE..1
(-2175 1300);
FORCEPROP 2 LAST $XR0 118 
J 0
(-2427 1300);
DISPLAY 0.638298 (-2427 1300);
PAINT MONO (-2427 1300);
FORCEPROP 1 LAST COMMENT_BODY TRUE
J 0
(-2050 1200);
DISPLAY 1.170213 (-2050 1200);
PAINT GREEN (-2050 1200);
DISPLAY INVISIBLE (-2050 1200);
FORCEPROP 1 LAST OFFPAGE TRUE
J 0
(-1850 1175);
DISPLAY 0.872340 (-1850 1175);
DISPLAY INVISIBLE (-1850 1175);
FORCEPROP 2 LAST PATH I96
J 0
(-2125 1375);
DISPLAY 1.021277 (-2125 1375);
DISPLAY INVISIBLE (-2125 1375);
FORCEPROP 2 LAST CDS_LIB standard
J 0
(-2175 1300);
DISPLAY INVISIBLE (-2175 1300);
FORCEADD Q_RES..2
(900 2225);
FORCEPROP 1 LAST PART_NUMBER CS24322FB03
J 0
(940 2100);
DISPLAY 0.638298 (940 2100);
DISPLAY INVISIBLE (940 2100);
FORCEPROP 1 LAST PACK_TYPE 0402LF
J 0
(940 2050);
DISPLAY 0.638298 (940 2050);
FORCEPROP 1 LAST WATTAGE 1/16W
J 0
(940 2200);
DISPLAY 0.638298 (940 2200);
FORCEPROP 1 LAST TOLERANCE 1%
J 0
(945 2250);
DISPLAY 0.638298 (945 2250);
FORCEPROP 1 LAST MATERIAL CHIP
J 0
(940 2150);
DISPLAY 0.638298 (940 2150);
FORCEPROP 1 LAST VALUE 4.32K
J 0
(945 2300);
DISPLAY 0.638298 (945 2300);
FORCEPROP 1 LAST LOCATION R4016
J 0
(945 2350);
DISPLAY 0.638298 (945 2350);
FORCEPROP 1 LASTPIN (900 2325) $PN 1
J 0
(905 2287);
DISPLAY 0.787234 (905 2287);
PAINT MONO (905 2287);
FORCEPROP 1 LASTPIN (900 2125) $PN 2
J 0
(905 2135);
DISPLAY 0.787234 (905 2135);
PAINT MONO (905 2135);
FORCEPROP 2 LAST CDS_LIB pure_quanta
J 0
(900 2225);
DISPLAY INVISIBLE (900 2225);
FORCEPROP 1 LAST PATH I97
J 0
(950 2400);
DISPLAY 0.978723 (950 2400);
PAINT WHITE (950 2400);
DISPLAY INVISIBLE (950 2400);
FORCEPROP 0 LAST $SEC 1
J 0
(950 2400);
DISPLAY 0.680851 (950 2400);
PAINT MONO (950 2400);
DISPLAY INVISIBLE (950 2400);
FORCEPROP 0 LAST CDS_SEC 1
J 0
(950 2400);
DISPLAY 1.021277 (950 2400);
DISPLAY INVISIBLE (950 2400);
FORCEADD Q_RES..2
(900 1850);
FORCEPROP 1 LAST PART_NUMBER CS21002FB06
J 0
(940 1725);
DISPLAY 0.638298 (940 1725);
DISPLAY INVISIBLE (940 1725);
FORCEPROP 1 LAST PACK_TYPE 0402LF
J 0
(940 1675);
DISPLAY 0.638298 (940 1675);
FORCEPROP 1 LAST VALUE 1K
J 0
(945 1925);
DISPLAY 0.638298 (945 1925);
FORCEPROP 1 LAST WATTAGE 1/16W
J 0
(940 1825);
DISPLAY 0.638298 (940 1825);
FORCEPROP 1 LAST MATERIAL CHIP
J 0
(940 1775);
DISPLAY 0.638298 (940 1775);
FORCEPROP 1 LAST TOLERANCE 1%
J 0
(945 1875);
DISPLAY 0.638298 (945 1875);
FORCEPROP 1 LAST LOCATION R4019
J 0
(945 1975);
DISPLAY 0.638298 (945 1975);
FORCEPROP 1 LASTPIN (900 1950) $PN 1
J 0
(905 1912);
DISPLAY 0.787234 (905 1912);
PAINT MONO (905 1912);
FORCEPROP 1 LASTPIN (900 1750) $PN 2
J 0
(905 1760);
DISPLAY 0.787234 (905 1760);
PAINT MONO (905 1760);
FORCEPROP 1 LAST PATH I98
J 0
(950 2025);
DISPLAY 0.978723 (950 2025);
PAINT WHITE (950 2025);
DISPLAY INVISIBLE (950 2025);
FORCEPROP 2 LAST CDS_LIB pure_quanta
J 0
(900 1850);
DISPLAY INVISIBLE (900 1850);
FORCEPROP 0 LAST $SEC 1
J 0
(950 2025);
DISPLAY 0.680851 (950 2025);
PAINT MONO (950 2025);
DISPLAY INVISIBLE (950 2025);
FORCEPROP 0 LAST CDS_SEC 1
J 0
(950 2025);
DISPLAY 1.021277 (950 2025);
DISPLAY INVISIBLE (950 2025);
FORCEADD QUANTA_TITLE_BLOCK_C..1
(4700 -3250);
FORCEPROP 0 LAST CDS_CON_LAST_MODIFIED Fri Aug 25 14:03:48 2023
J 0
(2815 -3235);
DISPLAY INVISIBLE (2815 -3235);
FORCEPROP 1 LAST CUSTOM_TXT_CDS <CON_LAST_MODIFIED>
J 0
(2815 -3235);
DISPLAY 0.978723 (2815 -3235);
FORCEPROP 2 LAST CUSTOM_TXT_CDS <XR_PAGE_TITLE>
J 0
(-3190 2000);
DISPLAY 0.638298 (-3190 2000);
PAINT PINK (-3190 2000);
DISPLAY INVISIBLE (-3190 2000);
FORCEPROP 1 LAST CUSTOM_TXT_CDS <NAME_2>
J 0
(1525 -3200);
FORCEPROP 1 LAST CUSTOM_TXT_CDS <NAME_1>
J 0
(1525 -3075);
FORCEPROP 1 LAST CUSTOM_TXT_CDS <Q_NUMBER>
J 0
(3297 -3147);
DISPLAY 1.212766 (3297 -3147);
FORCEPROP 1 LAST CUSTOM_TXT_CDS <Q_PROJ>
J 0
(2318 -3148);
DISPLAY 1.212766 (2318 -3148);
FORCEPROP 1 LAST CUSTOM_TXT_CDS <Q_REV>
J 0
(4516 -3147);
DISPLAY 1.212766 (4516 -3147);
FORCEPROP 1 LAST CUSTOM_TXT_CDS <CON_PAGE_NUM> OF <CON_TOTAL_PAGES>
J 0
(4254 -3232);
DISPLAY 0.978723 (4254 -3232);
FORCEPROP 1 LAST Q_TITLE GTL2014(2/2)
J 0
(-4666 -3224);
DISPLAY 2.446809 (-4666 -3224);
PAINT GREEN (-4666 -3224);
FORCEPROP 1 LAST Q_DEPT 
J 1
(937 -3201);
DISPLAY 1.957447 (937 -3201);
PAINT GREEN (937 -3201);
FORCEPROP 2 LAST CDS_XR_PAGE_TITLE CR-226 : @S9S_MB_2U_LIB.S9S_MB_2U(SCH_1):PAGE226
J 0
(-3190 2000);
DISPLAY 0.638298 (-3190 2000);
PAINT PINK (-3190 2000);
DISPLAY INVISIBLE (-3190 2000);
FORCEPROP 2 LAST CDS_LIB pure_quanta
J 0
(4700 -3250);
DISPLAY INVISIBLE (4700 -3250);
FORCEPROP 1 LAST CDS_LMAN_SYM_OUTLINE -9475,6775,100,-125
J 0
(4700 -3250);
DISPLAY 0.468085 (4700 -3250);
PAINT GREEN (4700 -3250);
DISPLAY INVISIBLE (4700 -3250);
FORCEPROP 2 LAST PAGE_BORDER TRUE
J 0
(-3190 2000);
DISPLAY 0.638298 (-3190 2000);
PAINT PINK (-3190 2000);
DISPLAY INVISIBLE (-3190 2000);
FORCEPROP 1 LAST COMMENT_BODY TRUE
J 0
(4712 -3263);
DISPLAY 0.978723 (4712 -3263);
PAINT GREEN (4712 -3263);
DISPLAY INVISIBLE (4712 -3263);
WIRE 16 -1 (-225 2175)(-225 2125);
WIRE 16 -1 (900 2425)(900 2325);
WIRE 16 -1 (-1250 1000)(-1250 1050);
WIRE 16 -1 (-75 1875)(-75 1800);
WIRE 16 -1 (900 1625)(900 1650);
WIRE 16 -1 (1625 1525)(1625 1550);
WIRE 16 -1 (-2125 1400)(-1125 1400);
FORCEPROP 0 LAST CDS_PHYS_NET_NAME PWRGD_CPUPWRGD_LVC1
J 0
(-2100 1442);
PAINT MONO (-2100 1442);
DISPLAY INVISIBLE (-2100 1442);
FORCEPROP 0 LAST SIG_NAME PWRGD_CPUPWRGD_LVC1
J 0
(-1985 1410);
DISPLAY 0.680851 (-1985 1410);
PAINT WHITE (-1985 1410);
WIRE 16 -1 (-2125 1350)(-1125 1350);
FORCEPROP 0 LAST CDS_PHYS_NET_NAME H_CPU_RMCA_LVC1_R_N
J 0
(-2100 1392);
PAINT MONO (-2100 1392);
DISPLAY INVISIBLE (-2100 1392);
FORCEPROP 0 LAST SIG_NAME H_CPU_RMCA_LVC1_R_N
J 0
(-1985 1360);
DISPLAY 0.680851 (-1985 1360);
PAINT WHITE (-1985 1360);
WIRE 16 -1 (-2125 1300)(-1650 1300);
FORCEPROP 0 LAST CDS_PHYS_NET_NAME H_CPU_CATERR_LVC1_R_N
J 0
(-2100 1342);
PAINT MONO (-2100 1342);
DISPLAY INVISIBLE (-2100 1342);
FORCEPROP 0 LAST SIG_NAME H_CPU_CATERR_LVC1_R_N
J 0
(-1985 1310);
DISPLAY 0.680851 (-1985 1310);
PAINT WHITE (-1985 1310);
WIRE 16 -1 (-1650 1300)(-1125 1300);
WIRE 16 -1 (-1650 1300)(-1650 1250);
WIRE 16 -1 (-1650 1250)(-1125 1250);
WIRE 16 -1 (-1250 1150)(-1125 1150);
WIRE 16 -1 (-1250 1150)(-1250 1100);
WIRE 16 -1 (-1250 1100)(-1125 1100);
WIRE 16 -1 (-1250 1100)(-1250 1050);
WIRE 16 -1 (-1125 1050)(-1250 1050);
WIRE 16 2175 (750 1125)(1400 1125);
WIRE 16 2175 (1400 1275)(1400 1125);
WIRE 16 2175 (750 1275)(750 1125);
WIRE 16 2175 (750 1275)(1400 1275);
WIRE 16 -1 (950 1200)(600 1200);
WIRE 16 -1 (600 1250)(-325 1250);
FORCEPROP 2 LAST SIG_NAME H_CPU_CATERR_LVC2_BMC_R_N
J 0
(-185 1260);
DISPLAY 0.638298 (-185 1260);
PAINT WHITE (-185 1260);
WIRE 16 -1 (600 1250)(600 1200);
WIRE 16 -1 (950 1300)(-325 1300);
FORCEPROP 0 LAST CDS_PHYS_NET_NAME RST_CPU0_DRAM_EF_PLD_N
J 0
(-300 1342);
PAINT MONO (-300 1342);
DISPLAY INVISIBLE (-300 1342);
FORCEPROP 0 LAST SIG_NAME H_CPU_CATERR_LVC2_R1_N
J 0
(-185 1310);
DISPLAY 0.680851 (-185 1310);
PAINT WHITE (-185 1310);
WIRE 16 -1 (-325 1350)(950 1350);
FORCEPROP 0 LAST CDS_PHYS_NET_NAME RST_CPU0_DRAM_CD_PLD_N
J 0
(-300 1392);
PAINT MONO (-300 1392);
DISPLAY INVISIBLE (-300 1392);
FORCEPROP 0 LAST SIG_NAME H_CPU_RMCA_LVC2_R1_N
J 0
(-185 1360);
DISPLAY 0.680851 (-185 1360);
PAINT WHITE (-185 1360);
WIRE 16 -1 (-325 1400)(950 1400);
FORCEPROP 0 LAST CDS_PHYS_NET_NAME RST_CPU0_DRAM_AB_PLD_N
J 0
(-300 1442);
PAINT MONO (-300 1442);
DISPLAY INVISIBLE (-300 1442);
FORCEPROP 0 LAST SIG_NAME PWRGD_CPUPWRGD_LVC2_R
J 0
(-185 1410);
DISPLAY 0.680851 (-185 1410);
PAINT WHITE (-185 1410);
WIRE 16 -1 (825 1500)(-325 1500);
FORCEPROP 2 LAST SIG_NAME PD_CPU0_ERRS_DIR
J 0
(-200 1510);
DISPLAY 0.446809 (-200 1510);
PAINT WHITE (-200 1510);
WIRE 16 -1 (825 1500)(825 1550);
WIRE 16 -1 (1050 1550)(825 1550);
WIRE 16 -1 (525 1750)(525 1650);
WIRE 16 -1 (525 1650)(900 1650);
WIRE 16 -1 (900 1650)(900 1750);
WIRE 16 2175 (800 1675)(1275 1675);
WIRE 16 2175 (1275 2600)(1275 1675);
WIRE 16 2175 (800 2600)(800 1675);
WIRE 16 2175 (800 2600)(1275 2600);
WIRE 16 -1 (-325 1650)(-225 1650);
WIRE 16 -1 (-225 1650)(-225 2125);
WIRE 16 -1 (-225 2125)(-75 2125);
WIRE 16 -1 (-75 2075)(-75 2125);
WIRE 16 -1 (1150 1200)(2575 1200);
FORCEPROP 0 LAST CDS_PHYS_NET_NAME RST_CPU0_DRAM_EF_PLD_N
J 0
(1175 1242);
PAINT MONO (1175 1242);
DISPLAY INVISIBLE (1175 1242);
FORCEPROP 0 LAST SIG_NAME H_CPU_CATERR_LVC2_BMC_N
J 0
(1615 1210);
DISPLAY 0.680851 (1615 1210);
PAINT WHITE (1615 1210);
WIRE 16 -1 (1625 1550)(1250 1550);
WIRE 16 -1 (-325 1600)(300 1600);
FORCEPROP 2 LAST SIG_NAME P0V62_CPU0_ERRS_VREF
J 0
(-200 1610);
DISPLAY 0.446809 (-200 1610);
PAINT WHITE (-200 1610);
WIRE 16 -1 (300 1600)(300 2000);
WIRE 16 -1 (300 2000)(525 2000);
WIRE 16 -1 (525 2000)(525 1950);
WIRE 16 -1 (900 2000)(525 2000);
WIRE 16 -1 (900 2000)(900 1950);
WIRE 16 -1 (900 2125)(900 2000);
WIRE 16 -1 (1150 1300)(2575 1300);
FORCEPROP 0 LAST CDS_PHYS_NET_NAME RST_CPU0_DRAM_EF_PLD_N
J 0
(1175 1342);
PAINT MONO (1175 1342);
DISPLAY INVISIBLE (1175 1342);
FORCEPROP 0 LAST SIG_NAME H_CPU_CATERR_LVC2_R2_N
J 0
(1615 1310);
DISPLAY 0.680851 (1615 1310);
PAINT WHITE (1615 1310);
WIRE 16 -1 (1150 1350)(2575 1350);
FORCEPROP 0 LAST CDS_PHYS_NET_NAME RST_CPU0_DRAM_CD_PLD_N
J 0
(1175 1392);
PAINT MONO (1175 1392);
DISPLAY INVISIBLE (1175 1392);
FORCEPROP 0 LAST SIG_NAME H_CPU_RMCA_LVC2_R2_N
J 0
(1615 1360);
DISPLAY 0.680851 (1615 1360);
PAINT WHITE (1615 1360);
WIRE 16 -1 (1150 1400)(2575 1400);
FORCEPROP 0 LAST CDS_PHYS_NET_NAME RST_CPU0_DRAM_AB_PLD_N
J 0
(1175 1442);
PAINT MONO (1175 1442);
DISPLAY INVISIBLE (1175 1442);
FORCEPROP 0 LAST SIG_NAME PWRGD_CPUPWRGD_LVC2_R1
J 0
(1615 1410);
DISPLAY 0.680851 (1615 1410);
PAINT WHITE (1615 1410);
DOT 1 (-1250 1100);
DOT 1 (-1650 1300);
DOT 1 (900 2000);
DOT 1 (900 1650);
DOT 1 (-225 2125);
DOT 1 (-1250 1050);
DOT 1 (525 2000);
FORCENOTE
202120302 ADD R4621
(600 1025) 0;
DISPLAY LEFT (600 1025);
DISPLAY 1.021277 (600 1025);
PAINT PINK (600 1025);
FORCENOTE
20211206 CHANGE R4016,R4019
(1325 2500) 0;
DISPLAY LEFT (1325 2500);
DISPLAY 1.595745 (1325 2500);
PAINT PINK (1325 2500);
FORCENOTE
20210902 MODIFY FOR GT
(-4450 2975) 0;
DISPLAY LEFT (-4450 2975);
DISPLAY 2.510638 (-4450 2975);
PAINT PINK (-4450 2975);
QUIT
